;LEADER: 12 
;HEADER: 
;CODE  : ASCII 
;FILE  : t6mg_pdb_a_v02_0109_1330-1-8.drl for board t6mg_pdb_a_v02_0109_1330.brd ... layers TOP and BOTTOM
;   Holesize 1. = 10.000000 Tolerance = +3.000000/-3.000000 PLATED MILS Quantity = 1901
;   Holesize 2. = 22.000000 Tolerance = +3.000000/-3.000000 PLATED MILS Quantity = 96
;   Holesize 3. = 28.000000 Tolerance = +2.000000/-2.000000 PLATED MILS Quantity = 328
;   Holesize 4. = 30.000000 Tolerance = +2.000000/-2.000000 PLATED MILS Quantity = 528
;   Holesize 5. = 36.000000 Tolerance = +3.000000/-3.000000 PLATED MILS Quantity = 72
;   Holesize 6. = 39.000000 Tolerance = +3.000000/-3.000000 PLATED MILS Quantity = 32
;   Holesize 7. = 43.000000 Tolerance = +3.000000/-3.000000 PLATED MILS Quantity = 11
;   Holesize 8. = 44.000000 Tolerance = +3.000000/-3.000000 PLATED MILS Quantity = 384
;   Holesize 9. = 57.000000 Tolerance = +3.000000/-3.000000 PLATED MILS Quantity = 20
;   Holesize 10. = 63.000000 Tolerance = +3.000000/-3.000000 PLATED MILS Quantity = 4
;   Holesize 11. = 52.000000 Tolerance = +2.000000/-2.000000 NON_PLATED MILS Quantity = 10
;   Holesize 12. = 95.000000 Tolerance = +2.000000/-2.000000 NON_PLATED MILS Quantity = 4
;   Holesize 13. = 99.000000 Tolerance = +2.000000/-2.000000 NON_PLATED MILS Quantity = 24
;   Holesize 14. = 126.000000 Tolerance = +2.000000/-2.000000 NON_PLATED MILS Quantity = 4
;   Holesize 15. = 132.000000 Tolerance = +2.000000/-2.000000 NON_PLATED MILS Quantity = 8
;   Holesize 16. = 158.000000 Tolerance = +2.000000/-2.000000 NON_PLATED MILS Quantity = 12
;   Holesize 17. = 205.000000 Tolerance = +2.000000/-2.000000 NON_PLATED MILS Quantity = 1
;   Holesize 18. = 315.000000 Tolerance = +4.000000/-4.000000 NON_PLATED MILS Quantity = 12
%
G90
X0003001Y0052034
X0003001Y0100034
X0003001Y0150034
X0003001Y0200034
X0003001Y0250034
X0003001Y0300034
X0003001Y0350034
X0003001Y0400034
X0003001Y0450034
X0003001Y0500034
X0003001Y0550034
X0003001Y0600034
X0003001Y0650034
X0003001Y0700034
X0003001Y0750034
X0003001Y0800034
X0003001Y0850034
X0003001Y0900034
X0003001Y0950034
X0003001Y1000034
X0003001Y1050034
X0003001Y1100034
X0003001Y1150034
X0003001Y1200034
X0003001Y1250034
X0003001Y1300034
X0003001Y1350034
X0003001Y1400034
X0003001Y1450034
X0003001Y1500034
X0003001Y1550034
X0003006Y1594602
X0003001Y1650034
X0003012Y1610165
X0003001Y1700034
X0003001Y1750034
X0003001Y1800034
X0003001Y1850034
X0003001Y1900034
X0003001Y1950034
X0003001Y2000034
X0003001Y2050034
X0026833Y2067866
X0076833Y2067866
X0080376Y1768566
X0080376Y1772098
X0080376Y1775609
X0106819Y1802230
X0108819Y1812118
X0108819Y1824470
X0107373Y1780544
X0107355Y1770437
X0107220Y1791589
X0107391Y1794460
X0085376Y1796236
X0080376Y1796163
X0075376Y1796236
X0070376Y1796383
X0054948Y1755171
X0055080Y1762982
X0055544Y1770835
X0056425Y1778371
X0091460Y1765062
X0088837Y1771103
X0105669Y1815227
X0099294Y1789947
X0099068Y1760827
X0099103Y1765722
X0098873Y1780542
X0099047Y1785571
X0093771Y1748227
X0011541Y1562330
X0016552Y1638005
X0011153Y1638435
X0107006Y1452651
X0108574Y1463389
X0095236Y1453321
X0105455Y1472894
X0106921Y1419492
X0106962Y1434041
X0106763Y1444599
X0097465Y1447919
X0097825Y1419492
X0097403Y1424340
X0096996Y1438980
X0096993Y1443743
X0096510Y1395382
X0045244Y1289067
X0045413Y1283724
X0045244Y1305787
X0045281Y1310893
X0045267Y1294203
X0045350Y1299697
X0045581Y1278420
X0067568Y1307829
X0054543Y1308995
X0061866Y1342104
X0070340Y1328203
X0061866Y1309190
X0046980Y1330843
X0046980Y1320843
X0046980Y1315843
X0046980Y1325843
X0100719Y1306810
X0100719Y1318810
X0046980Y1335843
X0046980Y1340843
X0046980Y1345843
X0100719Y1324810
X0100719Y1346065
X0100719Y1312810
X0100719Y1336810
X0054130Y1313763
X0067568Y1296654
X0063061Y1296312
X0054543Y1296513
X0057458Y1253378
X0058416Y1272383
X0058356Y1279812
X0059127Y1257647
X0100719Y1330810
X0049441Y1238962
X0096684Y1081791
X0108468Y1129286
X0107215Y1072208
X0107235Y1081791
X0105152Y1118381
X0082763Y1060051
X0107351Y1093484
X0108779Y1105760
X0098652Y1096403
X0096904Y1067515
X0096774Y1072226
X0096949Y1087095
X0096948Y1092036
X0105684Y1125919
X0063577Y1019115
X0060815Y1019026
X0102611Y0972220
X0105395Y0972040
X0079499Y1014871
X0076446Y1014871
X0100687Y0999391
X0098139Y0990959
X0070865Y0860278
X0070865Y0866278
X0089338Y0878294
X0070865Y0890116
X0070865Y0872278
X0091294Y0926951
X0070865Y0897750
X0048467Y0869278
X0048433Y0866179
X0092633Y0907404
X0091733Y0899382
X0105087Y0754126
X0101244Y0774100
X0102960Y0672823
X0096308Y0696622
X0059236Y0670758
X0054483Y0679810
X0057124Y0675327
X0107173Y0735219
X0107025Y0725368
X0095775Y0751469
X0106935Y0745139
X0079536Y0685710
X0079520Y0682439
X0086187Y0680710
X0086673Y0685710
X0081563Y0705437
X0088681Y0704108
X0061888Y0666012
X0098124Y0745139
X0098564Y0715937
X0098591Y0720745
X0097534Y0735248
X0097443Y0739962
X0015984Y0578849
X0010914Y0578848
X0013441Y0495961
X0109475Y0434743
X0106709Y0391219
X0106836Y0376461
X0094347Y0421562
X0093223Y0417736
X0105451Y0406795
X0101990Y0426104
X0097643Y0396024
X0097985Y0391220
X0097457Y0371909
X0097536Y0376580
X0109054Y0058250
X0107263Y0072244
X0108672Y0086150
X0157558Y0051426
X0104350Y0062293
X0175219Y0003002
X0125219Y0003002
X0104116Y0082557
X0158901Y0085017
X0159417Y0091281
X0106958Y0026285
X0107037Y0034687
X0107405Y0049898
X0101430Y0041803
X0102646Y0049461
X0108082Y0038899
X0097417Y0037438
X0097417Y0032853
X0106335Y0022580
X0025219Y0018752
X0162384Y0056744
X0162586Y0068130
X0161742Y0072497
X0075219Y0018752
X0166500Y0126110
X0166500Y0118626
X0166500Y0111407
X0166329Y0140623
X0166500Y0132705
X0166329Y0148066
X0173928Y0126110
X0173928Y0118626
X0173928Y0111407
X0173757Y0140623
X0173928Y0132705
X0173757Y0148066
X0169500Y0111407
X0169500Y0118626
X0169500Y0126110
X0169329Y0148066
X0169500Y0132705
X0169329Y0140623
X0176928Y0111407
X0176928Y0118626
X0176928Y0126110
X0176757Y0148066
X0176928Y0132705
X0176757Y0140623
X0161339Y0088108
X0166329Y0156102
X0166329Y0163621
X0173757Y0156102
X0173757Y0163621
X0169329Y0163621
X0169329Y0156102
X0176757Y0163621
X0176757Y0156102
X0178033Y0261594
X0178033Y0268813
X0175033Y0268813
X0175033Y0261594
X0178033Y0282892
X0177862Y0290810
X0177862Y0298253
X0178033Y0276297
X0175033Y0276297
X0174862Y0298253
X0174862Y0290810
X0175033Y0282892
X0177862Y0313808
X0177862Y0306289
X0174862Y0306289
X0174862Y0313808
X0165975Y0265783
X0165975Y0296140
X0165975Y0286803
X0165975Y0276298
X0165975Y0312307
X0165975Y0303868
X0168975Y0265783
X0168975Y0276298
X0168975Y0286803
X0168975Y0296140
X0168975Y0303868
X0168975Y0312307
X0158807Y0432969
X0111017Y0419566
X0159019Y0439268
X0114498Y0396207
X0156865Y0401207
X0161377Y0407575
X0161257Y0420869
X0161517Y0436119
X0156430Y0461714
X0156430Y0483012
X0156259Y0490930
X0156430Y0468933
X0156430Y0476417
X0156259Y0513928
X0156259Y0498373
X0156259Y0506409
X0159430Y0461714
X0159430Y0476417
X0159430Y0468933
X0159259Y0490930
X0159430Y0483012
X0159259Y0506409
X0159259Y0498373
X0159259Y0513928
X0160272Y0604773
X0157272Y0604773
X0160272Y0633416
X0160272Y0613574
X0160272Y0624079
X0157272Y0624079
X0157272Y0613574
X0157272Y0633416
X0160272Y0641144
X0160272Y0649583
X0157272Y0649583
X0157272Y0641144
X0113018Y0706356
X0156610Y0751063
X0115139Y0849240
X0112836Y0769122
X0158956Y0780982
X0111967Y0795261
X0159053Y0787280
X0161826Y0756757
X0161644Y0764231
X0161131Y0774878
X0155444Y0822725
X0162872Y0822725
X0162872Y0830209
X0155444Y0830209
X0171524Y0844722
X0162872Y0836804
X0155444Y0836804
X0162701Y0844722
X0155273Y0844722
X0179191Y0822725
X0179191Y0830209
X0171695Y0822725
X0171695Y0830209
X0179191Y0836804
X0171695Y0836804
X0179020Y0844722
X0165872Y0822725
X0158444Y0822725
X0158273Y0844722
X0165701Y0844722
X0158444Y0836804
X0165872Y0836804
X0158444Y0830209
X0165872Y0830209
X0174695Y0822725
X0182191Y0822725
X0182020Y0844722
X0174695Y0836804
X0182191Y0836804
X0174695Y0830209
X0182191Y0830209
X0174524Y0844722
X0161479Y0784141
X0176011Y0936829
X0175989Y0944537
X0184284Y0948331
X0171524Y0852165
X0162701Y0852165
X0155273Y0852165
X0171524Y0860201
X0171524Y0867720
X0162701Y0860201
X0155273Y0860201
X0162701Y0867720
X0155273Y0867720
X0179020Y0852165
X0179020Y0860201
X0179020Y0867720
X0158273Y0852165
X0165701Y0852165
X0158273Y0867720
X0165701Y0867720
X0158273Y0860201
X0165701Y0860201
X0182020Y0852165
X0174524Y0852165
X0182020Y0867720
X0182020Y0860201
X0174524Y0867720
X0174524Y0860201
X0175449Y0997660
X0175742Y0989958
X0175022Y0980281
X0175135Y0972490
X0175561Y0955964
X0175359Y0963486
X0175473Y1016296
X0175698Y1008730
X0175897Y1023997
X0175448Y1031766
X0188385Y1020810
X0184118Y1019280
X0184353Y1001556
X0184632Y0983423
X0184196Y0967371
X0166699Y0972924
X0166699Y0983439
X0166699Y0993944
X0166424Y1011298
X0166424Y1003570
X0166424Y1019737
X0163699Y0972924
X0163699Y0993944
X0163699Y0983439
X0163424Y1019737
X0163424Y1003570
X0163424Y1011298
X0158456Y1129045
X0112503Y1115860
X0159382Y1136151
X0156854Y1101031
X0162140Y1106853
X0164539Y1116135
X0169375Y1176256
X0169375Y1190335
X0169375Y1183740
X0153124Y1176256
X0160552Y1176256
X0160552Y1183740
X0160552Y1190335
X0153124Y1190335
X0153124Y1183740
X0160552Y1169037
X0153124Y1169037
X0169204Y1198253
X0160381Y1198253
X0152953Y1198253
X0176871Y1176256
X0176871Y1190335
X0176871Y1183740
X0176700Y1198253
X0156124Y1169037
X0163552Y1169037
X0156124Y1183740
X0156124Y1190335
X0163552Y1190335
X0163552Y1183740
X0163552Y1176256
X0156124Y1176256
X0172375Y1183740
X0172375Y1190335
X0172375Y1176256
X0155953Y1198253
X0163381Y1198253
X0172204Y1198253
X0179871Y1183740
X0179871Y1190335
X0179871Y1176256
X0179700Y1198253
X0155749Y1307733
X0155749Y1328753
X0155749Y1318248
X0155749Y1338090
X0155749Y1345818
X0158749Y1307733
X0158749Y1318248
X0158749Y1328753
X0158749Y1345818
X0158749Y1338090
X0159192Y1451105
X0155749Y1354257
X0158749Y1354257
X0170351Y1401324
X0164037Y1400226
X0158618Y1399448
X0176083Y1402321
X0159216Y1477124
X0113518Y1489571
X0159526Y1483434
X0162242Y1471380
X0163099Y1457084
X0162524Y1462651
X0157109Y1499221
X0164537Y1499221
X0164537Y1506440
X0157109Y1506440
X0154109Y1506440
X0170360Y1506440
X0161537Y1506440
X0161537Y1499221
X0154109Y1499221
X0156938Y1528437
X0157109Y1513924
X0157109Y1520519
X0164537Y1520519
X0164537Y1513924
X0164366Y1528437
X0170189Y1528437
X0161366Y1528437
X0161537Y1513924
X0161537Y1520519
X0170360Y1520519
X0170360Y1513924
X0154109Y1520519
X0154109Y1513924
X0153938Y1528437
X0156938Y1535880
X0156938Y1543916
X0156938Y1551435
X0164366Y1535880
X0164366Y1543916
X0164366Y1551435
X0170189Y1551435
X0161366Y1551435
X0161366Y1543916
X0161366Y1535880
X0170189Y1543916
X0170189Y1535880
X0153938Y1551435
X0153938Y1543916
X0153938Y1535880
X0180856Y1506440
X0173360Y1506440
X0177856Y1506440
X0180856Y1513924
X0180856Y1520519
X0180685Y1528437
X0173360Y1513924
X0173360Y1520519
X0173189Y1528437
X0177685Y1528437
X0177856Y1520519
X0177856Y1513924
X0180685Y1535880
X0180685Y1543916
X0180685Y1551435
X0173189Y1535880
X0173189Y1543916
X0173189Y1551435
X0177685Y1551435
X0177685Y1543916
X0177685Y1535880
X0158492Y1667763
X0158492Y1657248
X0158492Y1695333
X0158492Y1687605
X0158492Y1678268
X0158492Y1703772
X0161492Y1657248
X0161492Y1667763
X0161492Y1678268
X0161492Y1687605
X0161492Y1695333
X0161492Y1703772
X0156183Y1735240
X0165782Y1732903
X0168151Y1739208
X0150309Y1737009
X0144878Y1738861
X0173394Y1736051
X0163257Y1737619
X0159075Y1825087
X0159822Y1831380
X0156452Y1800821
X0162140Y1807740
X0163250Y1815631
X0161844Y1828225
X0152091Y1866003
X0159519Y1866003
X0152091Y1880706
X0152091Y1887301
X0168342Y1880706
X0168342Y1887301
X0159519Y1887301
X0159519Y1880706
X0159519Y1873222
X0168342Y1873222
X0152091Y1873222
X0151920Y1902662
X0151920Y1910698
X0168171Y1902662
X0168171Y1910698
X0159348Y1902662
X0159348Y1910698
X0151920Y1895219
X0159348Y1895219
X0168171Y1895219
X0151920Y1918217
X0159348Y1918217
X0168171Y1918217
X0175838Y1880706
X0175838Y1887301
X0175838Y1873222
X0175667Y1902662
X0175667Y1910698
X0175667Y1895219
X0175667Y1918217
X0162519Y1866003
X0155091Y1866003
X0155091Y1873222
X0171342Y1873222
X0162519Y1873222
X0162519Y1880706
X0162519Y1887301
X0171342Y1887301
X0171342Y1880706
X0155091Y1887301
X0155091Y1880706
X0171171Y1895219
X0162348Y1895219
X0154920Y1895219
X0162348Y1910698
X0162348Y1902662
X0171171Y1910698
X0171171Y1902662
X0154920Y1910698
X0154920Y1902662
X0171171Y1918217
X0162348Y1918217
X0154920Y1918217
X0178838Y1873222
X0178838Y1887301
X0178838Y1880706
X0178667Y1895219
X0178667Y1910698
X0178667Y1902662
X0178667Y1918217
X0109991Y2083607
X0159991Y2083607
X0209991Y2083607
X0259991Y2083607
X0221573Y2059050
X0231541Y2059050
X0231541Y2067489
X0221573Y2067489
X0242582Y2059050
X0255337Y2059050
X0255337Y2067489
X0242582Y2067489
X0267115Y2059050
X0267115Y2067489
X0236541Y2059050
X0226573Y2059050
X0226573Y2067489
X0236541Y2067489
X0260337Y2059050
X0247582Y2059050
X0247582Y2067489
X0260337Y2067489
X0272115Y2059050
X0272115Y2067489
X0221573Y2031480
X0231541Y2031480
X0221573Y2020965
X0231541Y2020965
X0231541Y2051322
X0221573Y2041985
X0221573Y2051322
X0231541Y2041985
X0242582Y2031480
X0242582Y2020965
X0255337Y2020965
X0255337Y2031480
X0242582Y2041985
X0242582Y2051322
X0255337Y2051322
X0255337Y2041985
X0267115Y2031480
X0267115Y2020965
X0267115Y2051322
X0267115Y2041985
X0236541Y2020965
X0226573Y2020965
X0236541Y2031480
X0226573Y2031480
X0236541Y2041985
X0226573Y2051322
X0226573Y2041985
X0236541Y2051322
X0260337Y2031480
X0260337Y2020965
X0247582Y2020965
X0247582Y2031480
X0260337Y2041985
X0260337Y2051322
X0247582Y2051322
X0247582Y2041985
X0272115Y2020965
X0272115Y2031480
X0272115Y2041985
X0272115Y2051322
X0279976Y1864565
X0280240Y1858668
X0293606Y1858668
X0273817Y1898327
X0278262Y1898327
X0282717Y1898327
X0287121Y1898327
X0292614Y1864565
X0292754Y1917148
X0300349Y1917148
X0292754Y1910232
X0300349Y1910232
X0307215Y1910412
X0307215Y1917328
X0292754Y1924103
X0300349Y1924103
X0307215Y1924283
X0303349Y1910232
X0295754Y1910232
X0303349Y1917148
X0295754Y1917148
X0303349Y1924103
X0295754Y1924103
X0286623Y1829400
X0291550Y1829846
X0281066Y1834569
X0258639Y1819074
X0258639Y1812119
X0258639Y1805203
X0250468Y1819074
X0250468Y1812119
X0250468Y1805203
X0267396Y1819077
X0267396Y1805206
X0267396Y1812122
X0258459Y1826219
X0250288Y1826219
X0267037Y1826222
X0258459Y1840090
X0258459Y1833135
X0267037Y1833138
X0267037Y1840093
X0250288Y1833135
X0250288Y1840090
X0270396Y1812122
X0270396Y1805206
X0270396Y1819077
X0253468Y1805203
X0253468Y1812119
X0253468Y1819074
X0261639Y1805203
X0261639Y1812119
X0261639Y1819074
X0253288Y1840090
X0253288Y1833135
X0270037Y1840093
X0270037Y1833138
X0261459Y1833135
X0261459Y1840090
X0270037Y1826222
X0253288Y1826219
X0261459Y1826219
X0274704Y1723196
X0289421Y1656558
X0284086Y1659883
X0294090Y1656558
X0289499Y1723735
X0284583Y1723465
X0279703Y1723398
X0219131Y1670386
X0219131Y1663167
X0218960Y1692383
X0219131Y1677870
X0219131Y1684465
X0218960Y1715381
X0218960Y1707862
X0218960Y1699826
X0242878Y1670386
X0222131Y1663167
X0238382Y1670386
X0229559Y1663167
X0229559Y1670386
X0222131Y1670386
X0226559Y1670386
X0226559Y1663167
X0235382Y1670386
X0242707Y1692383
X0242878Y1684465
X0242878Y1677870
X0238382Y1677870
X0238211Y1692383
X0238382Y1684465
X0229559Y1684465
X0229559Y1677870
X0229388Y1692383
X0222131Y1684465
X0222131Y1677870
X0221960Y1692383
X0226388Y1692383
X0226559Y1677870
X0226559Y1684465
X0235382Y1684465
X0235211Y1692383
X0235382Y1677870
X0242707Y1715381
X0242707Y1707862
X0242707Y1699826
X0238211Y1699826
X0229388Y1699826
X0221960Y1699826
X0238211Y1715381
X0238211Y1707862
X0229388Y1707862
X0229388Y1715381
X0221960Y1707862
X0221960Y1715381
X0226388Y1715381
X0226388Y1707862
X0235211Y1707862
X0235211Y1715381
X0226388Y1699826
X0235211Y1699826
X0245878Y1670386
X0245878Y1677870
X0245878Y1684465
X0245707Y1692383
X0245707Y1699826
X0245707Y1707862
X0245707Y1715381
X0261564Y1668347
X0261564Y1659908
X0261564Y1652180
X0265759Y1697613
X0254718Y1697613
X0265759Y1676593
X0265759Y1687108
X0254718Y1687108
X0254718Y1676593
X0254457Y1722140
X0265498Y1722140
X0265759Y1714678
X0254718Y1714678
X0254718Y1706950
X0265759Y1706950
X0273342Y1668347
X0273342Y1652180
X0273342Y1659908
X0251718Y1676593
X0251718Y1687108
X0251718Y1697613
X0251718Y1706950
X0251718Y1714678
X0251457Y1722140
X0258564Y1652180
X0258564Y1659908
X0258564Y1668347
X0262759Y1687108
X0262759Y1676593
X0262759Y1697613
X0262759Y1706950
X0262759Y1714678
X0262498Y1722140
X0270342Y1659908
X0270342Y1652180
X0270342Y1668347
X0261564Y1621823
X0261564Y1642843
X0261564Y1632338
X0273342Y1621823
X0273342Y1642843
X0273342Y1632338
X0258564Y1621823
X0258564Y1632338
X0258564Y1642843
X0270342Y1621823
X0270342Y1632338
X0270342Y1642843
X0301734Y1513883
X0302267Y1524401
X0279990Y1479435
X0275521Y1479435
X0270234Y1482760
X0291054Y1543211
X0295675Y1543211
X0300392Y1543211
X0304870Y1543211
X0263939Y1548010
X0263939Y1534139
X0263939Y1541055
X0278400Y1548190
X0271534Y1548010
X0285995Y1548190
X0278400Y1534319
X0278400Y1541235
X0271534Y1534139
X0271534Y1541055
X0285995Y1534319
X0285995Y1541235
X0260939Y1541055
X0260939Y1534139
X0260939Y1548010
X0282995Y1541235
X0282995Y1534319
X0268534Y1541055
X0268534Y1534139
X0275400Y1541235
X0275400Y1534319
X0282995Y1548190
X0268534Y1548010
X0275400Y1548190
X0309823Y1472957
X0309464Y1480102
X0309823Y1466002
X0309823Y1459086
X0292715Y1480099
X0292895Y1472954
X0301066Y1472954
X0300886Y1480099
X0292895Y1459083
X0292895Y1465999
X0301066Y1465999
X0301066Y1459083
X0309464Y1493973
X0309464Y1487018
X0292715Y1487015
X0292715Y1493970
X0300886Y1493970
X0300886Y1487015
X0304066Y1459083
X0304066Y1465999
X0295895Y1465999
X0295895Y1459083
X0303886Y1480099
X0304066Y1472954
X0295895Y1472954
X0295715Y1480099
X0303886Y1487015
X0303886Y1493970
X0295715Y1493970
X0295715Y1487015
X0270579Y1374626
X0275052Y1374715
X0279518Y1374543
X0284240Y1374544
X0289210Y1305634
X0283808Y1308959
X0294133Y1305634
X0219214Y1287272
X0219214Y1294491
X0219349Y1308924
X0219214Y1301975
X0219178Y1316842
X0219178Y1332321
X0219178Y1324285
X0219178Y1339840
X0229642Y1287272
X0222214Y1287272
X0226642Y1287272
X0229642Y1301975
X0238465Y1301975
X0229777Y1308924
X0238600Y1308924
X0229642Y1294491
X0238465Y1294491
X0222214Y1301975
X0222349Y1308924
X0222214Y1294491
X0242961Y1294491
X0235465Y1294491
X0226642Y1294491
X0243096Y1308924
X0242961Y1301975
X0235600Y1308924
X0226777Y1308924
X0235465Y1301975
X0226642Y1301975
X0229606Y1324285
X0238429Y1324285
X0229606Y1332321
X0238429Y1332321
X0229606Y1316842
X0238429Y1316842
X0222178Y1324285
X0222178Y1332321
X0222178Y1316842
X0242925Y1316842
X0235429Y1316842
X0226606Y1316842
X0242925Y1332321
X0242925Y1324285
X0235429Y1332321
X0226606Y1332321
X0235429Y1324285
X0226606Y1324285
X0229606Y1339840
X0238429Y1339840
X0222178Y1339840
X0242925Y1339840
X0235429Y1339840
X0226606Y1339840
X0267622Y1282945
X0267622Y1272430
X0256581Y1272430
X0256581Y1282945
X0259581Y1282945
X0259581Y1272430
X0267622Y1293450
X0267622Y1302787
X0267622Y1310515
X0256581Y1293450
X0256581Y1302787
X0256581Y1310515
X0259581Y1310515
X0259581Y1302787
X0259581Y1293450
X0245961Y1301975
X0246096Y1308924
X0245961Y1294491
X0267622Y1318954
X0256581Y1318954
X0259581Y1318954
X0245925Y1324285
X0245925Y1332321
X0245925Y1316842
X0245925Y1339840
X0270622Y1272430
X0270622Y1282945
X0270622Y1310515
X0270622Y1302787
X0270622Y1293450
X0270622Y1318954
X0262559Y1191777
X0267194Y1191777
X0272082Y1191777
X0276807Y1191777
X0238659Y1215296
X0231231Y1215296
X0238659Y1207777
X0238659Y1199741
X0231231Y1207777
X0231231Y1199741
X0254978Y1215296
X0247482Y1215296
X0254978Y1207777
X0254978Y1199741
X0247482Y1207777
X0247482Y1199741
X0228231Y1199741
X0228231Y1207777
X0235659Y1199741
X0235659Y1207777
X0228231Y1215296
X0235659Y1215296
X0244482Y1199741
X0244482Y1207777
X0251978Y1199741
X0251978Y1207777
X0244482Y1215296
X0251978Y1215296
X0287182Y1184455
X0287182Y1192183
X0284182Y1192183
X0284182Y1184455
X0287182Y1200622
X0284182Y1200622
X0303691Y1184526
X0295721Y1184312
X0295721Y1192040
X0303691Y1192254
X0300691Y1192254
X0292721Y1192040
X0292721Y1184312
X0300691Y1184526
X0309159Y1192254
X0309159Y1184526
X0303691Y1200693
X0295721Y1200479
X0292721Y1200479
X0300691Y1200693
X0309159Y1200693
X0309678Y1053262
X0292698Y1131146
X0288188Y1131146
X0282958Y1134471
X0242677Y1124900
X0242677Y1135415
X0232709Y1124900
X0232709Y1135415
X0235709Y1135415
X0235709Y1124900
X0242677Y1145920
X0232709Y1145920
X0235709Y1145920
X0260473Y1124613
X0260473Y1135128
X0251433Y1135271
X0251433Y1124756
X0254433Y1124756
X0254433Y1135271
X0245677Y1135415
X0245677Y1124900
X0263473Y1135128
X0263473Y1124613
X0260473Y1145633
X0251433Y1145776
X0254433Y1145776
X0245677Y1145920
X0263473Y1145633
X0269821Y1124471
X0269821Y1134986
X0272821Y1134986
X0272821Y1124471
X0269821Y1145491
X0272821Y1145491
X0295874Y0956442
X0291194Y0956442
X0285966Y0959767
X0290107Y1016162
X0294617Y1016162
X0281124Y1016162
X0285666Y1016162
X0234339Y0959673
X0241767Y0959673
X0241767Y0967157
X0241767Y0973752
X0234339Y0973752
X0234339Y0967157
X0241767Y0952454
X0234339Y0952454
X0231339Y0952454
X0238767Y0952454
X0231339Y0967157
X0231339Y0973752
X0238767Y0973752
X0238767Y0967157
X0238767Y0959673
X0231339Y0959673
X0241596Y0981670
X0234168Y0981670
X0241596Y0997149
X0241596Y0989113
X0234168Y0997149
X0234168Y0989113
X0231168Y0989113
X0231168Y0997149
X0238596Y0989113
X0238596Y0997149
X0231168Y0981670
X0238596Y0981670
X0241596Y1004668
X0234168Y1004668
X0231168Y1004668
X0238596Y1004668
X0258086Y0959673
X0258086Y0973752
X0258086Y0967157
X0250590Y0959673
X0250590Y0973752
X0250590Y0967157
X0247590Y0967157
X0247590Y0973752
X0247590Y0959673
X0255086Y0967157
X0255086Y0973752
X0255086Y0959673
X0257915Y0981670
X0257915Y0997149
X0257915Y0989113
X0250419Y0981670
X0250419Y0997149
X0250419Y0989113
X0247419Y0989113
X0247419Y0997149
X0247419Y0981670
X0254915Y0989113
X0254915Y0997149
X0254915Y0981670
X0257915Y1004668
X0250419Y1004668
X0247419Y1004668
X0254915Y1004668
X0307194Y1020657
X0307078Y1007303
X0307274Y1001286
X0307143Y1014094
X0307129Y1027081
X0306999Y1033718
X0262766Y0967106
X0262766Y0959859
X0262621Y0974386
X0262621Y0990553
X0262621Y0982114
X0274544Y0967106
X0274544Y0959859
X0274399Y0974386
X0274399Y0990553
X0274399Y0982114
X0265621Y0974386
X0265766Y0959859
X0265766Y0967106
X0265621Y0982114
X0265621Y0990553
X0277399Y0974386
X0277544Y0959859
X0277544Y0967106
X0277399Y0982114
X0277399Y0990553
X0262766Y0949344
X0274544Y0949344
X0265766Y0949344
X0277544Y0949344
X0238396Y0862887
X0238396Y0855159
X0238396Y0871326
X0241396Y0871326
X0241396Y0855159
X0241396Y0862887
X0250174Y0855159
X0250174Y0862887
X0250174Y0871326
X0253174Y0871326
X0253174Y0862887
X0253174Y0855159
X0255687Y0812192
X0255837Y0823626
X0270070Y0812192
X0282737Y0782643
X0278184Y0782643
X0273114Y0785968
X0273305Y0847237
X0277788Y0847237
X0264181Y0847354
X0268686Y0847488
X0237012Y0754782
X0234012Y0754782
X0237012Y0762510
X0237012Y0770949
X0234012Y0770949
X0234012Y0762510
X0246980Y0754782
X0258021Y0754782
X0255021Y0754782
X0243980Y0754782
X0246980Y0762510
X0246980Y0770949
X0258021Y0762510
X0258021Y0770949
X0255021Y0770949
X0255021Y0762510
X0243980Y0770949
X0243980Y0762510
X0278955Y0672192
X0283340Y0672192
X0270109Y0672192
X0274514Y0672192
X0307146Y0652457
X0304146Y0652457
X0307146Y0661258
X0307146Y0681100
X0307146Y0671763
X0304146Y0671763
X0304146Y0681100
X0304146Y0661258
X0307146Y0688828
X0307146Y0697267
X0304146Y0697267
X0304146Y0688828
X0290984Y0607215
X0285348Y0610540
X0295509Y0607215
X0230963Y0608108
X0238391Y0608108
X0230963Y0601513
X0238391Y0601513
X0238391Y0594029
X0230963Y0594029
X0230792Y0631505
X0238220Y0631505
X0230792Y0623469
X0238220Y0623469
X0230792Y0616026
X0238220Y0616026
X0230792Y0639024
X0238220Y0639024
X0254710Y0608108
X0254710Y0601513
X0254710Y0594029
X0247214Y0608108
X0247214Y0601513
X0247214Y0594029
X0254539Y0631505
X0254539Y0623469
X0254539Y0616026
X0247043Y0631505
X0247043Y0623469
X0247043Y0616026
X0254539Y0639024
X0247043Y0639024
X0227963Y0594029
X0235391Y0594029
X0235391Y0601513
X0227963Y0601513
X0235391Y0608108
X0227963Y0608108
X0235220Y0616026
X0227792Y0616026
X0235220Y0623469
X0227792Y0623469
X0235220Y0631505
X0227792Y0631505
X0235220Y0639024
X0227792Y0639024
X0244214Y0594029
X0244214Y0601513
X0244214Y0608108
X0251710Y0594029
X0251710Y0601513
X0251710Y0608108
X0244043Y0616026
X0244043Y0623469
X0244043Y0631505
X0251539Y0616026
X0251539Y0623469
X0251539Y0631505
X0244043Y0639024
X0251539Y0639024
X0267433Y0624321
X0279044Y0624627
X0264433Y0624321
X0276044Y0624627
X0264166Y0581440
X0264166Y0572639
X0267166Y0572639
X0267166Y0581440
X0264166Y0609010
X0264166Y0601282
X0264166Y0591945
X0267166Y0591945
X0267166Y0601282
X0267166Y0609010
X0264166Y0617449
X0267166Y0617449
X0275944Y0581440
X0275944Y0572639
X0278944Y0572639
X0278944Y0581440
X0275944Y0601282
X0275944Y0609010
X0275944Y0591945
X0278944Y0591945
X0278944Y0609010
X0278944Y0601282
X0275944Y0617449
X0278944Y0617449
X0265737Y0473680
X0265722Y0463102
X0274991Y0463099
X0264516Y0497341
X0268938Y0497341
X0273405Y0497341
X0277776Y0497341
X0232548Y0461083
X0241371Y0482381
X0241200Y0490299
X0232548Y0482381
X0232377Y0490299
X0241371Y0468302
X0241371Y0475786
X0232548Y0468302
X0232548Y0475786
X0241200Y0513297
X0232377Y0513297
X0241200Y0497742
X0232377Y0497742
X0241200Y0505778
X0232377Y0505778
X0248867Y0482381
X0248696Y0490299
X0248867Y0468302
X0248867Y0475786
X0248696Y0513297
X0248696Y0497742
X0248696Y0505778
X0229548Y0461083
X0229548Y0475786
X0229548Y0468302
X0238371Y0475786
X0238371Y0468302
X0229377Y0490299
X0229548Y0482381
X0238200Y0490299
X0238371Y0482381
X0229377Y0505778
X0238200Y0505778
X0229377Y0497742
X0238200Y0497742
X0229377Y0513297
X0238200Y0513297
X0245867Y0475786
X0245867Y0468302
X0245696Y0490299
X0245867Y0482381
X0245696Y0505778
X0245696Y0497742
X0245696Y0513297
X0289569Y0524323
X0289569Y0516595
X0289569Y0532762
X0297537Y0516309
X0304966Y0516419
X0304966Y0524147
X0297537Y0524037
X0297537Y0532476
X0304966Y0532586
X0292569Y0532762
X0292569Y0516595
X0292569Y0524323
X0307966Y0532586
X0300537Y0532476
X0300537Y0524037
X0307966Y0524147
X0307966Y0516419
X0300537Y0516309
X0291002Y0432844
X0286665Y0432844
X0281569Y0436169
X0239746Y0410393
X0239746Y0399878
X0239746Y0417898
X0239746Y0396878
X0239746Y0407393
X0239746Y0420898
X0266040Y0410146
X0266040Y0399631
X0257572Y0399630
X0257572Y0410145
X0248714Y0410536
X0248714Y0400021
X0248714Y0418041
X0257572Y0417650
X0248714Y0397021
X0248714Y0407536
X0257572Y0407145
X0257572Y0396630
X0266040Y0417651
X0266040Y0396631
X0266040Y0407146
X0266040Y0420651
X0257572Y0420650
X0248714Y0421041
X0274531Y0410289
X0274531Y0399774
X0274531Y0417794
X0274531Y0396774
X0274531Y0407289
X0274531Y0420794
X0281193Y0256624
X0276617Y0256400
X0271547Y0260353
X0289895Y0322688
X0294506Y0322688
X0281074Y0322688
X0285513Y0322688
X0236537Y0259074
X0236366Y0266992
X0236366Y0274435
X0227714Y0259074
X0227543Y0266992
X0227543Y0274435
X0244033Y0259074
X0243862Y0266992
X0243862Y0274435
X0236537Y0252479
X0227714Y0252479
X0244033Y0252479
X0236366Y0289990
X0227543Y0289990
X0243862Y0289990
X0236366Y0282471
X0227543Y0282471
X0243862Y0282471
X0224714Y0252479
X0233537Y0252479
X0224543Y0274435
X0224543Y0266992
X0224714Y0259074
X0233366Y0274435
X0233366Y0266992
X0233537Y0259074
X0224543Y0282471
X0233366Y0282471
X0224543Y0289990
X0233366Y0289990
X0241033Y0252479
X0240862Y0274435
X0240862Y0266992
X0241033Y0259074
X0240862Y0282471
X0240862Y0289990
X0261596Y0268188
X0261596Y0259749
X0255818Y0268188
X0255818Y0259749
X0252818Y0259749
X0252818Y0268188
X0264596Y0259749
X0264596Y0268188
X0236537Y0244995
X0227714Y0237776
X0227714Y0244995
X0244033Y0244995
X0224714Y0244995
X0224714Y0237776
X0233537Y0244995
X0241033Y0244995
X0261596Y0221664
X0255818Y0221664
X0252818Y0221664
X0264596Y0221664
X0261596Y0242684
X0261596Y0232179
X0255818Y0242684
X0255818Y0232179
X0252818Y0232179
X0252818Y0242684
X0264596Y0232179
X0264596Y0242684
X0261596Y0252021
X0255818Y0252021
X0252818Y0252021
X0264596Y0252021
X0217732Y0156964
X0217732Y0173131
X0217732Y0164692
X0217732Y0161692
X0217732Y0170131
X0217732Y0153964
X0238741Y0156964
X0227700Y0156964
X0238741Y0173131
X0238741Y0164692
X0227700Y0173131
X0227700Y0164692
X0227700Y0161692
X0227700Y0170131
X0238741Y0161692
X0238741Y0170131
X0227700Y0153964
X0238741Y0153964
X0256861Y0156964
X0248083Y0156964
X0256861Y0173131
X0256861Y0164692
X0248083Y0173131
X0248083Y0164692
X0248083Y0161692
X0248083Y0170131
X0256861Y0161692
X0256861Y0170131
X0248083Y0153964
X0256861Y0153964
X0306267Y0241010
X0308057Y0248863
X0257125Y0115559
X0256947Y0128276
X0402512Y0017108
X0375219Y0003002
X0325219Y0003002
X0294483Y0082732
X0308651Y0078778
X0304151Y0078778
X0299687Y0078778
X0271943Y0147630
X0276523Y0147585
X0263086Y0147675
X0267420Y0147540
X0267627Y0115559
X0240955Y0056999
X0240955Y0064483
X0240784Y0078996
X0240955Y0071078
X0240784Y0094475
X0240784Y0101994
X0240784Y0086439
X0248451Y0056999
X0248451Y0064483
X0248280Y0078996
X0248451Y0071078
X0248280Y0094475
X0248280Y0101994
X0248280Y0086439
X0237955Y0056999
X0237955Y0071078
X0237784Y0078996
X0237955Y0064483
X0237784Y0086439
X0237784Y0101994
X0237784Y0094475
X0245451Y0056999
X0245451Y0071078
X0245280Y0078996
X0245451Y0064483
X0245280Y0086439
X0245280Y0101994
X0245280Y0094475
X0264104Y0054944
X0256566Y0054944
X0256566Y0068449
X0264104Y0068449
X0256566Y0057944
X0264104Y0057944
X0264104Y0065449
X0256566Y0065449
X0279754Y0054944
X0271572Y0054944
X0288102Y0054944
X0288102Y0068449
X0271572Y0068449
X0279754Y0068449
X0288102Y0057944
X0271572Y0057944
X0279754Y0057944
X0279754Y0065449
X0271572Y0065449
X0288102Y0065449
X0331403Y0051409
X0340373Y0051579
X0348289Y0050863
X0402512Y0117108
X0402512Y0067108
X0275219Y0003002
X0225219Y0003002
X0317567Y0078778
X0313089Y0078778
X0322005Y0078778
X0256566Y0048572
X0264104Y0048572
X0264104Y0045572
X0256566Y0045572
X0288102Y0048572
X0271572Y0048572
X0279754Y0048572
X0279754Y0045572
X0271572Y0045572
X0288102Y0045572
X0333889Y0056021
X0338227Y0061559
X0345089Y0056190
X0387524Y0076847
X0359931Y0052189
X0379257Y0052158
X0372204Y0056126
X0402512Y0217108
X0402512Y0167108
X0314914Y0238162
X0324709Y0231580
X0320961Y0250105
X0320372Y0225979
X0331046Y0232021
X0321899Y0238137
X0318088Y0231820
X0362236Y0324983
X0361799Y0311938
X0402512Y0317108
X0402512Y0267108
X0329775Y0318634
X0329693Y0311980
X0332693Y0311980
X0332775Y0318634
X0329775Y0335272
X0329775Y0342461
X0329775Y0325935
X0332775Y0325935
X0332775Y0342461
X0332775Y0335272
X0329685Y0348655
X0332685Y0348655
X0340816Y0318634
X0340734Y0311980
X0343734Y0311980
X0343816Y0318634
X0340816Y0335272
X0340816Y0342461
X0340816Y0325935
X0343816Y0325935
X0343816Y0342461
X0343816Y0335272
X0340726Y0348655
X0343726Y0348655
X0314940Y0252083
X0368907Y0404308
X0363825Y0401768
X0328950Y0409216
X0374542Y0401282
X0326196Y0413982
X0342097Y0401684
X0320980Y0423225
X0374442Y0406857
X0323313Y0418313
X0335522Y0404033
X0402512Y0417108
X0402512Y0367108
X0402512Y0517108
X0402512Y0467108
X0313791Y0524432
X0313791Y0516704
X0313791Y0532871
X0322139Y0516632
X0322139Y0524360
X0322139Y0532799
X0325139Y0532799
X0316791Y0532871
X0316791Y0516704
X0316791Y0524432
X0325139Y0524360
X0325139Y0516632
X0320380Y0576491
X0342900Y0580126
X0321742Y0599041
X0333750Y0595326
X0337387Y0586230
X0331867Y0589810
X0317724Y0588250
X0329636Y0584715
X0319305Y0582111
X0336617Y0577978
X0402512Y0617108
X0402512Y0567108
X0356559Y0675167
X0344109Y0751809
X0354000Y0652170
X0402512Y0717108
X0402512Y0667108
X0315187Y0652457
X0315187Y0671763
X0315187Y0681100
X0315187Y0661258
X0315187Y0697267
X0315187Y0688828
X0318187Y0652457
X0318187Y0661258
X0318187Y0681100
X0318187Y0671763
X0318187Y0688828
X0318187Y0697267
X0327524Y0758020
X0376654Y0754748
X0334010Y0758588
X0386790Y0774338
X0382892Y0767710
X0339012Y0752859
X0329336Y0762693
X0331568Y0752967
X0362577Y0752783
X0402512Y0817108
X0402512Y0767108
X0328583Y0933262
X0343656Y0933725
X0336160Y0937262
X0326646Y0939788
X0323868Y0929978
X0318557Y0941178
X0324098Y0946104
X0321425Y0951577
X0332527Y0943746
X0329938Y0948756
X0402512Y0917108
X0402512Y0867108
X0335677Y1048904
X0345578Y1047844
X0324246Y1051786
X0402512Y1017108
X0402512Y0967108
X0318235Y1020657
X0318315Y1001286
X0318119Y1007303
X0318184Y1014094
X0318170Y1027081
X0318040Y1033718
X0310143Y1014094
X0310274Y1001286
X0310078Y1007303
X0310194Y1020657
X0309999Y1033718
X0310129Y1027081
X0321184Y1014094
X0321119Y1007303
X0321315Y1001286
X0321235Y1020657
X0321040Y1033718
X0321170Y1027081
X0317592Y1053050
X0344099Y1106798
X0337509Y1109598
X0326558Y1126368
X0328989Y1121090
X0402512Y1117108
X0402512Y1067108
X0312698Y1172804
X0312527Y1162266
X0371523Y1204725
X0386816Y1179841
X0383276Y1184136
X0373674Y1199967
X0376472Y1194999
X0379335Y1189778
X0325796Y1162266
X0402512Y1217108
X0402512Y1167108
X0323403Y1172804
X0312159Y1184526
X0312159Y1192254
X0312159Y1200693
X0320936Y1192253
X0320936Y1184525
X0317936Y1184525
X0317936Y1192253
X0320936Y1200692
X0317936Y1200692
X0329619Y1284016
X0327932Y1289221
X0321978Y1282086
X0327452Y1279447
X0402512Y1317108
X0402512Y1267108
X0354391Y1329686
X0354391Y1350706
X0354391Y1340201
X0366169Y1329686
X0366169Y1350706
X0366169Y1340201
X0351391Y1329686
X0351391Y1340201
X0351391Y1350706
X0363169Y1329686
X0363169Y1340201
X0363169Y1350706
X0374681Y1365620
X0373564Y1352548
X0402512Y1417108
X0402512Y1367108
X0354391Y1360043
X0354391Y1376210
X0354391Y1367771
X0366169Y1360043
X0366169Y1376210
X0366169Y1367771
X0351391Y1360043
X0351391Y1367771
X0351391Y1376210
X0363169Y1360043
X0363169Y1367771
X0363169Y1376210
X0350690Y1403243
X0344130Y1401670
X0334646Y1400804
X0325636Y1399114
X0314183Y1403423
X0313894Y1513883
X0402512Y1517108
X0402512Y1467108
X0312823Y1459086
X0312823Y1466002
X0312464Y1480102
X0312823Y1472957
X0312464Y1487018
X0312464Y1493973
X0402512Y1617108
X0402512Y1567108
X0367829Y1566108
X0335963Y1573797
X0333474Y1566686
X0355364Y1570990
X0312077Y1575871
X0348245Y1575241
X0343402Y1572080
X0361011Y1568890
X0323720Y1570924
X0348710Y1570187
X0402512Y1717108
X0402512Y1667108
X0402512Y1817108
X0402512Y1767108
X0329887Y1752081
X0323813Y1753231
X0374431Y1901397
X0366306Y1899864
X0352337Y1887285
X0402512Y1917108
X0402512Y1867108
X0314810Y1910412
X0314810Y1917328
X0314810Y1924283
X0317810Y1910412
X0310215Y1910412
X0310215Y1924283
X0317810Y1924283
X0310215Y1917328
X0317810Y1917328
X0332399Y1926787
X0340336Y1922409
X0344402Y1911123
X0369748Y1921795
X0379403Y1917261
X0345537Y1916558
X0363411Y1923459
X0358318Y1920680
X0363361Y1918313
X0374775Y1919243
X0402512Y2017108
X0402512Y1967108
X0320045Y2005215
X0314562Y2009087
X0324803Y2005272
X0309991Y2083607
X0359991Y2083607
X0402512Y2067108
M00
X0065354Y1878740
X0055511Y1874803
X0051574Y1864960
X0055511Y1855117
X0075197Y1855117
X0079134Y1864960
X0075197Y1874803
X0065354Y1851180
X0065354Y1528740
X0055511Y1524803
X0051574Y1514960
X0055511Y1505117
X0065354Y1501180
X0075197Y1505117
X0079134Y1514960
X0075197Y1524803
X0065354Y1178740
X0055511Y1174803
X0051574Y1164960
X0055511Y1155117
X0075197Y1155117
X0079134Y1164960
X0075197Y1174803
X0065354Y1151180
X0065354Y0828740
X0055511Y0824803
X0051574Y0814960
X0055511Y0805117
X0065354Y0801180
X0075197Y0805117
X0079134Y0814960
X0075197Y0824803
X0065354Y0478740
X0055511Y0474803
X0051574Y0464960
X0055511Y0455117
X0075197Y0455117
X0079134Y0464960
X0075197Y0474803
X0065354Y0451180
X0065354Y0128740
X0055511Y0124803
X0051574Y0114960
X0055511Y0105117
X0065354Y0101180
X0075197Y0105117
X0079134Y0114960
X0075197Y0124803
X0307087Y2057283
X0297244Y2053346
X0293307Y2043503
X0297244Y2033660
X0307087Y2029723
X0307086Y1707284
X0297243Y1703347
X0293306Y1693504
X0297243Y1683661
X0307086Y1679724
X0307086Y1357284
X0297243Y1353347
X0293306Y1343504
X0297243Y1333661
X0307086Y1329724
X0307086Y0840945
X0297243Y0837008
X0293306Y0827165
X0297243Y0817322
X0307086Y0813385
X0307086Y0490945
X0297243Y0487008
X0293306Y0477165
X0297243Y0467322
X0307086Y0463385
X0307086Y0140945
X0297243Y0137008
X0293306Y0127165
X0297243Y0117322
X0307086Y0113385
X0316929Y0117322
X0320866Y0127165
X0316929Y0137008
X0316929Y0467322
X0320866Y0477165
X0316929Y0487008
X0316929Y0817322
X0320866Y0827165
X0316929Y0837008
X0316929Y1333661
X0320866Y1343504
X0316929Y1353347
X0316929Y1683661
X0320866Y1693504
X0316929Y1703347
X0316930Y2033660
X0320867Y2043503
X0316930Y2053346
M00
X0007673Y0750671
X0007673Y0742797
X0007673Y0734923
X0007673Y0727049
X0007673Y0719175
X0007673Y0711301
X0007673Y0703427
X0007673Y0845160
X0007673Y0837286
X0007673Y0829412
X0007673Y0821538
X0007673Y0813664
X0007673Y0805790
X0007673Y0797915
X0007673Y0790041
X0007673Y0782167
X0007673Y0774293
X0007673Y0766419
X0007673Y0758545
X0007673Y0947522
X0007673Y0939648
X0007673Y0931774
X0007673Y0923900
X0007673Y0916026
X0007673Y0908152
X0007673Y0900278
X0007673Y0892404
X0007673Y0884530
X0007673Y0876656
X0007673Y0868782
X0007673Y0860908
X0007673Y0853034
X0007673Y1026262
X0007673Y1018388
X0007673Y1010514
X0007673Y1002640
X0007673Y0994766
X0007673Y0979018
X0007673Y0971144
X0007673Y0963270
X0007673Y0955396
X0007677Y1148306
X0007677Y1140432
X0007677Y1132558
X0007677Y1124684
X0007677Y1116810
X0007677Y1108936
X0007677Y1101062
X0007677Y1093188
X0007677Y1085314
X0007677Y1077440
X0007677Y1069566
X0007677Y1061692
X0007677Y1250669
X0007677Y1242795
X0007677Y1234921
X0007677Y1227047
X0007677Y1219173
X0007677Y1211299
X0007677Y1203425
X0007677Y1195551
X0007677Y1187677
X0007677Y1179803
X0007677Y1171929
X0007677Y1164055
X0007677Y1156180
X0007677Y1337283
X0007677Y1329409
X0007677Y1321535
X0007677Y1313661
X0007677Y1305787
X0007677Y1297913
X0007677Y1290039
X0007677Y1282165
X0007677Y1274291
X0007677Y1266417
X0007677Y1258543
X0007677Y1384527
X0007677Y1376653
X0007677Y1368779
X0007677Y1360905
X0007677Y1353031
X0025393Y1388464
X0025393Y1380590
X0025393Y1372716
X0025393Y1364842
X0025393Y1356968
X0015551Y1388464
X0015551Y1380590
X0015551Y1372716
X0015551Y1364842
X0015551Y1356968
X0033267Y1384527
X0033267Y1376653
X0033267Y1368779
X0033267Y1360905
X0033267Y1353031
X0025393Y1349094
X0015551Y1349094
X0033267Y1337283
X0033267Y1329409
X0033267Y1321535
X0033267Y1313661
X0033267Y1305787
X0033267Y1297913
X0033267Y1290039
X0033267Y1282165
X0033267Y1274291
X0033267Y1266417
X0033267Y1258543
X0025393Y1333346
X0025393Y1325472
X0025393Y1317598
X0025393Y1309724
X0025393Y1301850
X0025393Y1293976
X0025393Y1286102
X0025393Y1278228
X0025393Y1270354
X0025393Y1262480
X0025393Y1254606
X0015551Y1333346
X0015551Y1325472
X0015551Y1317598
X0015551Y1309724
X0015551Y1301850
X0015551Y1293976
X0015551Y1286102
X0015551Y1278228
X0015551Y1270354
X0015551Y1262480
X0015551Y1254606
X0033267Y1250669
X0033267Y1242795
X0033267Y1234921
X0033267Y1227047
X0033267Y1219173
X0033267Y1211299
X0033267Y1203425
X0033267Y1195551
X0033267Y1187677
X0033267Y1179803
X0033267Y1171929
X0033267Y1164055
X0033267Y1156180
X0025393Y1246732
X0025393Y1238858
X0025393Y1230984
X0025393Y1223110
X0025393Y1215236
X0025393Y1207362
X0025393Y1199488
X0025393Y1191614
X0025393Y1183740
X0025393Y1175866
X0025393Y1167992
X0025393Y1160118
X0025393Y1152244
X0015551Y1246732
X0015551Y1238858
X0015551Y1230984
X0015551Y1223110
X0015551Y1215236
X0015551Y1207362
X0015551Y1199488
X0015551Y1191614
X0015551Y1183740
X0015551Y1175866
X0015551Y1167992
X0015551Y1160118
X0015551Y1152244
X0033267Y1148306
X0033267Y1140432
X0033267Y1132558
X0033267Y1124684
X0033267Y1116810
X0033267Y1108936
X0033267Y1101062
X0033267Y1093188
X0033267Y1085314
X0033267Y1077440
X0033267Y1069566
X0033267Y1061692
X0025393Y1144370
X0025393Y1136496
X0025393Y1128622
X0025393Y1120748
X0025393Y1112873
X0025393Y1104999
X0025393Y1097125
X0025393Y1089251
X0025393Y1081377
X0025393Y1073503
X0025393Y1065629
X0015551Y1144370
X0015551Y1136496
X0015551Y1128622
X0015551Y1120748
X0015551Y1112873
X0015551Y1104999
X0015551Y1097125
X0015551Y1089251
X0015551Y1081377
X0015551Y1073503
X0015551Y1065629
X0025389Y1030199
X0025389Y1022325
X0025389Y1014451
X0025389Y1006577
X0025389Y0998703
X0025389Y0990829
X0015547Y1030199
X0015547Y1022325
X0015547Y1014451
X0015547Y1006577
X0015547Y0998703
X0015547Y0990829
X0033263Y1026262
X0033263Y1018388
X0033263Y1010514
X0033263Y1002640
X0033263Y0994766
X0033263Y0979018
X0033263Y0971144
X0033263Y0963270
X0033263Y0955396
X0025389Y0975081
X0025389Y0967207
X0025389Y0959333
X0015547Y0975081
X0015547Y0967207
X0015547Y0959333
X0033263Y0947522
X0033263Y0939648
X0033263Y0931774
X0033263Y0923900
X0033263Y0916026
X0033263Y0908152
X0033263Y0900278
X0033263Y0892404
X0033263Y0884530
X0033263Y0876656
X0033263Y0868782
X0033263Y0860908
X0033263Y0853034
X0025389Y0951459
X0025389Y0943585
X0025389Y0935711
X0025389Y0927837
X0025389Y0919963
X0025389Y0912089
X0025389Y0904215
X0025389Y0896341
X0025389Y0888467
X0025389Y0880593
X0025389Y0872719
X0025389Y0864845
X0025389Y0856971
X0015547Y0951459
X0015547Y0943585
X0015547Y0935711
X0015547Y0927837
X0015547Y0919963
X0015547Y0912089
X0015547Y0904215
X0015547Y0896341
X0015547Y0888467
X0015547Y0880593
X0015547Y0872719
X0015547Y0864845
X0015547Y0856971
X0033263Y0845160
X0033263Y0837286
X0033263Y0829412
X0033263Y0821538
X0033263Y0813664
X0033263Y0805790
X0033263Y0797915
X0033263Y0790041
X0033263Y0782167
X0033263Y0774293
X0033263Y0766419
X0033263Y0758545
X0025389Y0849097
X0025389Y0841223
X0025389Y0833349
X0025389Y0825475
X0025389Y0817601
X0025389Y0809727
X0025389Y0801853
X0025389Y0793979
X0025389Y0786105
X0025389Y0778231
X0025389Y0770357
X0025389Y0762483
X0025389Y0754608
X0015547Y0849097
X0015547Y0841223
X0015547Y0833349
X0015547Y0825475
X0015547Y0817601
X0015547Y0809727
X0015547Y0801853
X0015547Y0793979
X0015547Y0786105
X0015547Y0778231
X0015547Y0770357
X0015547Y0762483
X0015547Y0754608
X0033263Y0750671
X0033263Y0742797
X0033263Y0734923
X0033263Y0727049
X0033263Y0719175
X0033263Y0711301
X0033263Y0703427
X0025389Y0746734
X0025389Y0738860
X0025389Y0730986
X0025389Y0723112
X0025389Y0715238
X0025389Y0707364
X0015547Y0746734
X0015547Y0738860
X0015547Y0730986
X0015547Y0723112
X0015547Y0715238
X0015547Y0707364
M00
X0203385Y0021890
X0203385Y0032520
X0193385Y0021890
X0193385Y0032520
X0183385Y0021890
X0183385Y0032520
X0173385Y0021890
X0173385Y0032520
X0203385Y0196890
X0203385Y0207520
X0193385Y0196890
X0193385Y0207520
X0183385Y0196890
X0183385Y0207520
X0173385Y0196890
X0173385Y0207520
X0203385Y0371890
X0203385Y0382520
X0193385Y0371890
X0193385Y0382520
X0183385Y0371890
X0183385Y0382520
X0173385Y0371890
X0173385Y0382520
X0203386Y0546890
X0193386Y0546890
X0183386Y0546890
X0173386Y0546890
X0203386Y0557520
X0193386Y0557520
X0183386Y0557520
X0173386Y0557520
X0203386Y0721890
X0203386Y0732520
X0193386Y0721890
X0193386Y0732520
X0183386Y0721890
X0183386Y0732520
X0173386Y0721890
X0173386Y0732520
X0203385Y0896890
X0203385Y0907520
X0193385Y0896890
X0193385Y0907520
X0183385Y0896890
X0183385Y0907520
X0173385Y0896890
X0173385Y0907520
X0203385Y1071890
X0203385Y1082520
X0193385Y1071890
X0193385Y1082520
X0183385Y1071890
X0183385Y1082520
X0173385Y1071890
X0173385Y1082520
X0203385Y1246890
X0193385Y1246890
X0183385Y1246890
X0173385Y1246890
X0203385Y1257520
X0193385Y1257520
X0183385Y1257520
X0173385Y1257520
X0203385Y1421890
X0203385Y1432520
X0193385Y1421890
X0193385Y1432520
X0183385Y1421890
X0183385Y1432520
X0173385Y1421890
X0173385Y1432520
X0203385Y1596890
X0203385Y1607520
X0193385Y1596890
X0193385Y1607520
X0183385Y1596890
X0183385Y1607520
X0173385Y1596890
X0173385Y1607520
X0203385Y1771890
X0203385Y1782520
X0193385Y1771890
X0193385Y1782520
X0183385Y1771890
X0183385Y1782520
X0173385Y1771890
X0173385Y1782520
X0203385Y1946890
X0193385Y1946890
X0183385Y1946890
X0173385Y1946890
X0203385Y1957520
X0193385Y1957520
X0183385Y1957520
X0173385Y1957520
X0303385Y1957520
X0293385Y1957520
X0283385Y1957520
X0273385Y1957520
X0263385Y1957520
X0253385Y1957520
X0243385Y1957520
X0233385Y1957520
X0223385Y1957520
X0213385Y1957520
X0303385Y1946890
X0293385Y1946890
X0283385Y1946890
X0273385Y1946890
X0263385Y1946890
X0253385Y1946890
X0243385Y1946890
X0233385Y1946890
X0223385Y1946890
X0213385Y1946890
X0303385Y1782520
X0303385Y1771890
X0293385Y1782520
X0293385Y1771890
X0283385Y1782520
X0283385Y1771890
X0273385Y1782520
X0273385Y1771890
X0263385Y1782520
X0263385Y1771890
X0253385Y1782520
X0253385Y1771890
X0243385Y1771890
X0243385Y1782520
X0233385Y1771890
X0233385Y1782520
X0223385Y1771890
X0223385Y1782520
X0213385Y1771890
X0213385Y1782520
X0303385Y1607520
X0303385Y1596890
X0293385Y1607520
X0293385Y1596890
X0283385Y1607520
X0283385Y1596890
X0273385Y1607520
X0273385Y1596890
X0263385Y1607520
X0263385Y1596890
X0253385Y1607520
X0253385Y1596890
X0243385Y1596890
X0243385Y1607520
X0233385Y1596890
X0233385Y1607520
X0223385Y1596890
X0223385Y1607520
X0213385Y1596890
X0213385Y1607520
X0303385Y1432520
X0303385Y1421890
X0293385Y1432520
X0293385Y1421890
X0283385Y1432520
X0283385Y1421890
X0273385Y1432520
X0273385Y1421890
X0263385Y1432520
X0263385Y1421890
X0253385Y1432520
X0253385Y1421890
X0243385Y1421890
X0243385Y1432520
X0233385Y1421890
X0233385Y1432520
X0223385Y1421890
X0223385Y1432520
X0213385Y1421890
X0213385Y1432520
X0303385Y1257520
X0293385Y1257520
X0283385Y1257520
X0273385Y1257520
X0263385Y1257520
X0253385Y1257520
X0243385Y1257520
X0233385Y1257520
X0223385Y1257520
X0213385Y1257520
X0303385Y1246890
X0293385Y1246890
X0283385Y1246890
X0273385Y1246890
X0263385Y1246890
X0253385Y1246890
X0243385Y1246890
X0233385Y1246890
X0223385Y1246890
X0213385Y1246890
X0303385Y1082520
X0303385Y1071890
X0293385Y1082520
X0293385Y1071890
X0283385Y1082520
X0283385Y1071890
X0273385Y1082520
X0273385Y1071890
X0263385Y1082520
X0263385Y1071890
X0253385Y1082520
X0253385Y1071890
X0243385Y1071890
X0243385Y1082520
X0233385Y1071890
X0233385Y1082520
X0223385Y1071890
X0223385Y1082520
X0213385Y1071890
X0213385Y1082520
X0303385Y0907520
X0303385Y0896890
X0293385Y0907520
X0293385Y0896890
X0283385Y0907520
X0283385Y0896890
X0273385Y0907520
X0273385Y0896890
X0263385Y0907520
X0263385Y0896890
X0253385Y0907520
X0253385Y0896890
X0243385Y0896890
X0243385Y0907520
X0233385Y0896890
X0233385Y0907520
X0223385Y0896890
X0223385Y0907520
X0213385Y0896890
X0213385Y0907520
X0303386Y0732520
X0303386Y0721890
X0293386Y0732520
X0293386Y0721890
X0283386Y0732520
X0283386Y0721890
X0273386Y0732520
X0273386Y0721890
X0263386Y0732520
X0263386Y0721890
X0253386Y0732520
X0253386Y0721890
X0243386Y0721890
X0243386Y0732520
X0233386Y0721890
X0233386Y0732520
X0223386Y0721890
X0223386Y0732520
X0213386Y0721890
X0213386Y0732520
X0303386Y0557520
X0293386Y0557520
X0283386Y0557520
X0273386Y0557520
X0263386Y0557520
X0253386Y0557520
X0243386Y0557520
X0233386Y0557520
X0223386Y0557520
X0213386Y0557520
X0303386Y0546890
X0293386Y0546890
X0283386Y0546890
X0273386Y0546890
X0263386Y0546890
X0253386Y0546890
X0243386Y0546890
X0233386Y0546890
X0223386Y0546890
X0213386Y0546890
X0303385Y0382520
X0303385Y0371890
X0293385Y0382520
X0293385Y0371890
X0283385Y0382520
X0283385Y0371890
X0273385Y0382520
X0273385Y0371890
X0263385Y0382520
X0263385Y0371890
X0253385Y0382520
X0253385Y0371890
X0243385Y0371890
X0243385Y0382520
X0233385Y0371890
X0233385Y0382520
X0223385Y0371890
X0223385Y0382520
X0213385Y0371890
X0213385Y0382520
X0303385Y0207520
X0303385Y0196890
X0293385Y0207520
X0293385Y0196890
X0283385Y0207520
X0283385Y0196890
X0273385Y0207520
X0273385Y0196890
X0263385Y0207520
X0263385Y0196890
X0253385Y0207520
X0253385Y0196890
X0243385Y0196890
X0243385Y0207520
X0233385Y0196890
X0233385Y0207520
X0223385Y0196890
X0223385Y0207520
X0213385Y0196890
X0213385Y0207520
X0313385Y0021890
X0323385Y0021890
X0313385Y0032520
X0323385Y0032520
X0362165Y0029705
X0362165Y0019705
X0357165Y0034705
X0357165Y0024705
X0352165Y0029705
X0352165Y0019705
X0347165Y0034705
X0347165Y0024705
X0342165Y0029705
X0342165Y0019705
X0337165Y0034705
X0337165Y0024705
X0303385Y0032520
X0303385Y0021890
X0293385Y0032520
X0293385Y0021890
X0283385Y0032520
X0283385Y0021890
X0273385Y0032520
X0273385Y0021890
X0263385Y0032520
X0263385Y0021890
X0253385Y0032520
X0253385Y0021890
X0243385Y0021890
X0243385Y0032520
X0233385Y0021890
X0233385Y0032520
X0223385Y0021890
X0223385Y0032520
X0213385Y0021890
X0213385Y0032520
X0313385Y0196890
X0323385Y0196890
X0313385Y0207520
X0323385Y0207520
X0362165Y0204705
X0362165Y0194705
X0357165Y0209705
X0357165Y0199705
X0352165Y0204705
X0352165Y0194705
X0347165Y0209705
X0347165Y0199705
X0342165Y0204705
X0342165Y0194705
X0337165Y0209705
X0337165Y0199705
X0313385Y0371890
X0323385Y0371890
X0313385Y0382520
X0323385Y0382520
X0362165Y0379705
X0362165Y0369705
X0357165Y0384705
X0357165Y0374705
X0352165Y0379705
X0352165Y0369705
X0347165Y0384705
X0347165Y0374705
X0342165Y0379705
X0342165Y0369705
X0337165Y0384705
X0337165Y0374705
X0313386Y0546890
X0323386Y0546890
X0362166Y0544705
X0357166Y0549705
X0352166Y0544705
X0347166Y0549705
X0342166Y0544705
X0337166Y0549705
X0313386Y0557520
X0323386Y0557520
X0362166Y0554705
X0357166Y0559705
X0352166Y0554705
X0347166Y0559705
X0342166Y0554705
X0337166Y0559705
X0313386Y0721890
X0323386Y0721890
X0313386Y0732520
X0323386Y0732520
X0362166Y0729705
X0362166Y0719705
X0357166Y0734705
X0357166Y0724705
X0352166Y0729705
X0352166Y0719705
X0347166Y0734705
X0347166Y0724705
X0342166Y0729705
X0342166Y0719705
X0337166Y0734705
X0337166Y0724705
X0313385Y0896890
X0323385Y0896890
X0313385Y0907520
X0323385Y0907520
X0362165Y0904705
X0362165Y0894705
X0357165Y0909705
X0357165Y0899705
X0352165Y0904705
X0352165Y0894705
X0347165Y0909705
X0347165Y0899705
X0342165Y0904705
X0342165Y0894705
X0337165Y0909705
X0337165Y0899705
X0313385Y1071890
X0323385Y1071890
X0313385Y1082520
X0323385Y1082520
X0362165Y1079705
X0362165Y1069705
X0357165Y1084705
X0357165Y1074705
X0352165Y1079705
X0352165Y1069705
X0347165Y1084705
X0347165Y1074705
X0342165Y1079705
X0342165Y1069705
X0337165Y1084705
X0337165Y1074705
X0313385Y1246890
X0323385Y1246890
X0362165Y1244705
X0357165Y1249705
X0352165Y1244705
X0347165Y1249705
X0342165Y1244705
X0337165Y1249705
X0313385Y1257520
X0323385Y1257520
X0362165Y1254705
X0357165Y1259705
X0352165Y1254705
X0347165Y1259705
X0342165Y1254705
X0337165Y1259705
X0313385Y1421890
X0323385Y1421890
X0313385Y1432520
X0323385Y1432520
X0362165Y1429705
X0362165Y1419705
X0357165Y1434705
X0357165Y1424705
X0352165Y1429705
X0352165Y1419705
X0347165Y1434705
X0347165Y1424705
X0342165Y1429705
X0342165Y1419705
X0337165Y1434705
X0337165Y1424705
X0313385Y1596890
X0323385Y1596890
X0313385Y1607520
X0323385Y1607520
X0362165Y1604705
X0362165Y1594705
X0357165Y1609705
X0357165Y1599705
X0352165Y1604705
X0352165Y1594705
X0347165Y1609705
X0347165Y1599705
X0342165Y1604705
X0342165Y1594705
X0337165Y1609705
X0337165Y1599705
X0313385Y1771890
X0323385Y1771890
X0313385Y1782520
X0323385Y1782520
X0362165Y1779705
X0362165Y1769705
X0357165Y1784705
X0357165Y1774705
X0352165Y1779705
X0352165Y1769705
X0347165Y1784705
X0347165Y1774705
X0342165Y1779705
X0342165Y1769705
X0337165Y1784705
X0337165Y1774705
X0313385Y1946890
X0323385Y1946890
X0362165Y1944705
X0357165Y1949705
X0352165Y1944705
X0347165Y1949705
X0342165Y1944705
X0337165Y1949705
X0313385Y1957520
X0323385Y1957520
X0362165Y1954705
X0357165Y1959705
X0352165Y1954705
X0347165Y1959705
X0342165Y1954705
X0337165Y1959705
M00
X0055254Y1612504
X0055254Y1602504
X0055254Y1592504
X0055254Y1582504
X0065254Y1607504
X0065254Y1597504
X0065254Y1587504
X0065254Y1577504
X0014073Y1619807
X0014073Y1570201
X0014073Y1610004
X0014073Y1580004
X0055254Y0554500
X0014073Y0561803
X0055254Y0544500
X0055254Y0534500
X0055254Y0524500
X0065254Y0549500
X0065254Y0539500
X0065254Y0529500
X0065254Y0519500
X0014073Y0512197
X0014073Y0552000
X0014073Y0522000
X0204069Y0152050
X0190289Y0152050
X0203542Y0073105
X0189762Y0073105
X0204137Y0247568
X0190357Y0247568
X0204597Y0331786
X0190817Y0331786
X0203541Y0421732
X0189761Y0421732
X0204333Y0506517
X0190553Y0506517
X0206668Y0598130
X0192888Y0598130
X0204596Y0681645
X0190816Y0681645
X0205626Y0774526
X0191846Y0774526
X0196311Y0947202
X0205386Y0856244
X0191606Y0856244
X0209296Y1032544
X0195516Y1032544
X0205030Y1122856
X0191250Y1122856
X0205122Y1206233
X0191342Y1206233
X0205626Y1299104
X0191846Y1299104
X0204332Y1380966
X0190552Y1380966
X0203243Y1474162
X0189463Y1474162
X0204859Y1557277
X0191079Y1557277
X0205923Y1648177
X0192143Y1648177
X0205387Y1731351
X0191607Y1731351
X0205310Y1823227
X0191530Y1823227
X0204069Y1900420
X0190289Y1900420
X0205310Y2043388
X0191530Y2043388
X0205905Y1998730
X0192125Y1998730
X0210091Y0947202
M00
X0054979Y0415500
X0054979Y0405500
X0054979Y0395500
X0054979Y0385500
X0064979Y0410500
X0064979Y0400500
X0064979Y0390500
X0064979Y0380500
X0054979Y0279500
X0054979Y0269500
X0054979Y0259500
X0064979Y0274500
X0064979Y0264500
X0064979Y0254500
X0054979Y0206500
X0054979Y0196500
X0054979Y0186500
X0054979Y0176500
X0064979Y0201500
X0064979Y0191500
X0064979Y0181500
X0064979Y0171500
X0054979Y0249500
X0064979Y0244500
X0054979Y0070500
X0054979Y0060500
X0064979Y0065500
X0064979Y0055500
X0054979Y0050500
X0054979Y0040500
X0064979Y0045500
X0064979Y0035500
M00
X0022756Y2035629
X0022756Y2023818
X0022756Y1960629
X0022756Y1878630
X0022756Y1866819
X0022756Y1948818
X0022480Y0340460
X0022480Y0328649
X0022480Y0316838
X0022756Y0125629
X0022756Y0113818
M00
X0119920Y0048071
X0119920Y0038071
X0119920Y0028071
X0119920Y0018071
X0139920Y0018071
X0139920Y0028071
X0139920Y0038071
X0139920Y0048071
X0119920Y0148071
X0119920Y0138071
X0119920Y0128071
X0119920Y0118071
X0119920Y0108071
X0119920Y0098071
X0119920Y0088071
X0119920Y0078071
X0119920Y0068071
X0119920Y0058071
X0139920Y0058071
X0139920Y0068071
X0139920Y0078071
X0139920Y0088071
X0139920Y0098071
X0139920Y0108071
X0139920Y0118071
X0139920Y0128071
X0139920Y0138071
X0139920Y0148071
X0119920Y0248071
X0119920Y0238071
X0119920Y0228071
X0119920Y0218071
X0119920Y0208071
X0119920Y0198071
X0119920Y0188071
X0119920Y0178071
X0119920Y0168071
X0119920Y0158071
X0139920Y0158071
X0139920Y0168071
X0139920Y0178071
X0139920Y0188071
X0139920Y0198071
X0139920Y0208071
X0139920Y0218071
X0139920Y0228071
X0139920Y0238071
X0139920Y0248071
X0119920Y0328071
X0119920Y0318071
X0119920Y0308071
X0119920Y0298071
X0119920Y0288071
X0119920Y0278071
X0119920Y0268071
X0119920Y0258071
X0139920Y0258071
X0139920Y0268071
X0139920Y0278071
X0139920Y0288071
X0139920Y0298071
X0139920Y0308071
X0139920Y0318071
X0139920Y0328071
X0119920Y0446102
X0119920Y0436102
X0119920Y0426102
X0119920Y0416102
X0119920Y0406102
X0119920Y0396102
X0119920Y0386102
X0119920Y0376102
X0119920Y0366102
X0139920Y0366102
X0139920Y0376102
X0139920Y0386102
X0139920Y0396102
X0139920Y0406102
X0139920Y0416102
X0139920Y0426102
X0139920Y0436102
X0139920Y0446102
X0119920Y0546102
X0119920Y0536102
X0119920Y0526102
X0119920Y0516102
X0119920Y0506102
X0119920Y0496102
X0119920Y0486102
X0119920Y0476102
X0119920Y0466102
X0119920Y0456102
X0139920Y0456102
X0139920Y0466102
X0139920Y0476102
X0139920Y0486102
X0139920Y0496102
X0139920Y0506102
X0139920Y0516102
X0139920Y0526102
X0139920Y0536102
X0139920Y0546102
X0119920Y0646102
X0119920Y0636102
X0119920Y0626102
X0119920Y0616102
X0119920Y0606102
X0119920Y0596102
X0119920Y0586102
X0119920Y0576102
X0119920Y0566102
X0119920Y0556102
X0139920Y0556102
X0139920Y0566102
X0139920Y0576102
X0139920Y0586102
X0139920Y0596102
X0139920Y0606102
X0139920Y0616102
X0139920Y0626102
X0139920Y0636102
X0139920Y0646102
X0119920Y0676102
X0119920Y0666102
X0119920Y0656102
X0139920Y0656102
X0139920Y0666102
X0139920Y0676102
X0119920Y0744134
X0119920Y0734134
X0119920Y0724134
X0119920Y0714134
X0139920Y0714134
X0139920Y0724134
X0139920Y0734134
X0139920Y0744134
X0119920Y0844134
X0119920Y0834134
X0119920Y0824134
X0119920Y0814134
X0119920Y0804134
X0119920Y0794134
X0119920Y0784134
X0119920Y0774134
X0119920Y0764134
X0119920Y0754134
X0139920Y0754134
X0139920Y0764134
X0139920Y0774134
X0139920Y0784134
X0139920Y0794134
X0139920Y0804134
X0139920Y0814134
X0139920Y0824134
X0139920Y0834134
X0139920Y0844134
X0119920Y0944134
X0119920Y0934134
X0119920Y0924134
X0119920Y0914134
X0119920Y0904134
X0119920Y0894134
X0119920Y0884134
X0119920Y0874134
X0119920Y0864134
X0119920Y0854134
X0139920Y0854134
X0139920Y0864134
X0139920Y0874134
X0139920Y0884134
X0139920Y0894134
X0139920Y0904134
X0139920Y0914134
X0139920Y0924134
X0139920Y0934134
X0139920Y0944134
X0119920Y1024134
X0119920Y1014134
X0119920Y1004134
X0119920Y0994134
X0119920Y0984134
X0119920Y0974134
X0119920Y0964134
X0119920Y0954134
X0139920Y0954134
X0139920Y0964134
X0139920Y0974134
X0139920Y0984134
X0139920Y0994134
X0139920Y1004134
X0139920Y1014134
X0139920Y1024134
X0119920Y1142165
X0119920Y1132165
X0119920Y1122165
X0119920Y1112165
X0119920Y1102165
X0119920Y1092165
X0119920Y1082165
X0119920Y1072165
X0119920Y1062165
X0139920Y1062165
X0139920Y1072165
X0139920Y1082165
X0139920Y1092165
X0139920Y1102165
X0139920Y1112165
X0139920Y1122165
X0139920Y1132165
X0139920Y1142165
X0119920Y1242165
X0119920Y1232165
X0119920Y1222165
X0119920Y1212165
X0119920Y1202165
X0119920Y1192165
X0119920Y1182165
X0119920Y1172165
X0119920Y1162165
X0119920Y1152165
X0139920Y1152165
X0139920Y1162165
X0139920Y1172165
X0139920Y1182165
X0139920Y1192165
X0139920Y1202165
X0139920Y1212165
X0139920Y1222165
X0139920Y1232165
X0139920Y1242165
X0119920Y1342165
X0119920Y1332165
X0119920Y1322165
X0119920Y1312165
X0119920Y1302165
X0119920Y1292165
X0119920Y1282165
X0119920Y1272165
X0119920Y1262165
X0119920Y1252165
X0139920Y1252165
X0139920Y1262165
X0139920Y1272165
X0139920Y1282165
X0139920Y1292165
X0139920Y1302165
X0139920Y1312165
X0139920Y1322165
X0139920Y1332165
X0139920Y1342165
X0119920Y1450197
X0119920Y1440197
X0119920Y1430197
X0119920Y1420197
X0119920Y1410197
X0139920Y1410197
X0139920Y1420197
X0139920Y1430197
X0139920Y1440197
X0139920Y1450197
X0119920Y1372165
X0119920Y1362165
X0119920Y1352165
X0139920Y1352165
X0139920Y1362165
X0139920Y1372165
X0119920Y1550197
X0119920Y1540197
X0119920Y1530197
X0119920Y1520197
X0119920Y1510197
X0119920Y1500197
X0119920Y1490197
X0119920Y1480197
X0119920Y1470197
X0119920Y1460197
X0139920Y1460197
X0139920Y1470197
X0139920Y1480197
X0139920Y1490197
X0139920Y1500197
X0139920Y1510197
X0139920Y1520197
X0139920Y1530197
X0139920Y1540197
X0139920Y1550197
X0119920Y1650197
X0119920Y1640197
X0119920Y1630197
X0119920Y1620197
X0119920Y1610197
X0119920Y1600197
X0119920Y1590197
X0119920Y1580197
X0119920Y1570197
X0119920Y1560197
X0139920Y1560197
X0139920Y1570197
X0139920Y1580197
X0139920Y1590197
X0139920Y1600197
X0139920Y1610197
X0139920Y1620197
X0139920Y1630197
X0139920Y1640197
X0139920Y1650197
X0119920Y1720197
X0119920Y1710197
X0119920Y1700197
X0119920Y1690197
X0119920Y1680197
X0119920Y1670197
X0119920Y1660197
X0139920Y1660197
X0139920Y1670197
X0139920Y1680197
X0139920Y1690197
X0139920Y1700197
X0139920Y1710197
X0139920Y1720197
X0119920Y1848228
X0119920Y1838228
X0119920Y1828228
X0119920Y1818228
X0119920Y1808228
X0119920Y1798228
X0119920Y1788228
X0119920Y1778228
X0119920Y1768228
X0119920Y1758228
X0139920Y1758228
X0139920Y1768228
X0139920Y1778228
X0139920Y1788228
X0139920Y1798228
X0139920Y1808228
X0139920Y1818228
X0139920Y1828228
X0139920Y1838228
X0139920Y1848228
X0119920Y1948228
X0119920Y1938228
X0119920Y1928228
X0119920Y1918228
X0119920Y1908228
X0119920Y1898228
X0119920Y1888228
X0119920Y1878228
X0119920Y1868228
X0119920Y1858228
X0139920Y1858228
X0139920Y1868228
X0139920Y1878228
X0139920Y1888228
X0139920Y1898228
X0139920Y1908228
X0139920Y1918228
X0139920Y1928228
X0139920Y1938228
X0139920Y1948228
X0119920Y2048228
X0119920Y2038228
X0119920Y2028228
X0119920Y2018228
X0119920Y2008228
X0119920Y1998228
X0119920Y1988228
X0119920Y1978228
X0119920Y1968228
X0119920Y1958228
X0139920Y1958228
X0139920Y1968228
X0139920Y1978228
X0139920Y1988228
X0139920Y1998228
X0139920Y2008228
X0139920Y2018228
X0139920Y2028228
X0139920Y2038228
X0139920Y2048228
X0119920Y2068228
X0119920Y2058228
X0139920Y2058228
X0139920Y2068228
M00
X0045056Y1784622
X0045056Y1768087
X0023402Y1784622
X0023402Y1768087
X0045056Y1801158
X0023402Y1801158
X0045056Y1817693
X0023402Y1817693
X0045056Y1751551
X0045056Y1735016
X0045056Y1718480
X0023402Y1751551
X0023402Y1735016
X0023402Y1718480
X0045056Y1701945
X0023402Y1701945
X0045056Y1685410
X0023402Y1685410
X0045056Y1668874
X0023402Y1668874
M00
X0045411Y1626008
X0045411Y1564000
X0045411Y0568004
X0045411Y0505996
M00
X0030473Y2047440
X0030473Y2012007
X0030473Y1972440
X0030473Y1890441
X0030473Y1855008
X0030473Y1937007
X0030197Y0352271
X0030197Y0305027
X0030473Y0137440
X0030473Y0102007
M00
X0020472Y1342598
X0020472Y1054606
X0020468Y0984333
X0020468Y0696341
M00
X0163385Y0027205
X0163385Y0202205
X0163385Y0377205
X0163386Y0552205
X0163386Y0727205
X0163385Y0902205
X0163385Y1077205
X0163385Y1252205
X0163385Y1427205
X0163385Y1602205
X0163385Y1777205
X0163385Y1952205
X0373385Y0032520
X0373385Y0207520
X0373385Y0382520
X0373386Y0557520
X0373386Y0732520
X0373385Y0907520
X0373385Y1082520
X0373385Y1257520
X0373385Y1432520
X0373385Y1607520
X0373385Y1782520
X0373385Y1957520
M00
X0030254Y1617504
X0030254Y1572504
X0030254Y0559500
X0030254Y0514500
M00
X0029979Y0420500
X0029979Y0375500
X0029979Y0284500
X0029979Y0211500
X0029979Y0166500
X0029979Y0239500
X0029979Y0075500
X0029979Y0030500
M00
X0065354Y1864960
X0065354Y1514960
X0065354Y1164960
X0065354Y0814960
X0065354Y0464960
X0065354Y0114960
X0307087Y2043503
X0307086Y1693504
X0307086Y1343504
X0307086Y0827165
X0307086Y0477165
X0307086Y0127165
M00
X0307086Y0308267
M00
X0359842Y0078780
X0359842Y0253780
X0359842Y0428779
X0359842Y0603779
X0359842Y0778780
X0359842Y0953780
X0359842Y1128779
X0359842Y1303780
X0359842Y1478780
X0359842Y1653780
X0359842Y1828779
X0359842Y2003780
M30
